(kicad_pcb
	(version 20260206)
	(generator "pcbnew")
	(generator_version "10.0")
	(general
		(thickness 1.6)
		(legacy_teardrops no)
	)
	(paper "A4")
	(title_block
		(title "netronome-mezz — pcbd0082-001_rev01_jul9_a.brd")
		(comment 1 "Open CloudServer (Microsoft) / footprints 524-533 of 714")
	)
	(layers
		(0 "F.Cu" signal "TOP")
		(4 "In1.Cu" signal "02_GND")
		(6 "In2.Cu" signal "03_SIG")
		(8 "In3.Cu" signal "04_SIG")
		(10 "In4.Cu" signal "05_GND")
		(12 "In5.Cu" signal "06_PWR1")
		(14 "In6.Cu" signal "07_SIG")
		(16 "In7.Cu" signal "08_SIG")
		(18 "In8.Cu" signal "09_GND")
		(2 "B.Cu" signal "BOTTOM")
		(9 "F.Adhes" user "F.Adhesive")
		(11 "B.Adhes" user "B.Adhesive")
		(13 "F.Paste" user "Package Geometry/Pastemask Top")
		(15 "B.Paste" user "Package Geometry/Pastemask Bottom")
		(5 "F.SilkS" user "Ref Des/Silkscreen Top")
		(7 "B.SilkS" user "Ref Des/Silkscreen Bottom")
		(1 "F.Mask" user "Board Geometry/Soldermask Top")
		(3 "B.Mask" user "Board Geometry/Soldermask Bottom")
		(17 "Dwgs.User" user "User.Drawings")
		(19 "Cmts.User" user "User.Comments")
		(21 "Eco1.User" user "User.Eco1")
		(23 "Eco2.User" user "User.Eco2")
		(25 "Edge.Cuts" user "Board Geometry/Outline")
		(27 "Margin" user)
		(31 "F.CrtYd" user "Package Geometry/Place Bound Top")
		(29 "B.CrtYd" user "Package Geometry/Place Bound Bottom")
		(35 "F.Fab" user "Ref Des/Assembly Top")
		(33 "B.Fab" user "Ref Des/Assembly Bottom")
		(45 "User.4" user "COMPVAL_TYPE_BOTTOM")
	)
	(footprint ""
		(layer "B.Cu")
		(at 28.321 32.639)
		(property "Reference" "R176"
			(at -0.15367 4.826 270)
			(unlocked yes)
			(layer "B.SilkS")
			(effects
				(font
					(size 0.7874 0.5842)
					(thickness 0.127)
				)
				(justify left mirror)
			)
		)
		(property "Value" "0"
			(at 0.148158 1.3462 270)
			(unlocked yes)
			(layer "B.Fab")
			(hide yes)
			(effects
				(font
					(size 1.27 0.9652)
					(thickness 0.000001)
				)
				(justify left mirror)
			)
		)
		(property "Device Type" "REST1111"
			(at 0.148158 1.3462 270)
			(unlocked yes)
			(layer "B.Fab")
			(hide yes)
			(effects
				(font
					(size 1.27 0.9652)
					(thickness 0.000001)
				)
				(justify left mirror)
			)
		)
		(duplicate_pad_numbers_are_jumpers no)
		(fp_poly
			(pts
				(xy -0.635 1.0668) (xy -0.635 -1.0668) (xy 0.635 -1.0668) (xy 0.635 1.0668)
			)
			(stroke
				(width 0)
				(type default)
			)
			(fill no)
			(layer "B.CrtYd")
		)
		(fp_line
			(start -0.254 -0.508)
			(end -0.254 0.508)
			(stroke
				(width 0.0254)
				(type default)
			)
			(layer "B.Fab")
		)
		(fp_line
			(start -0.254 0.508)
			(end 0.254 0.508)
			(stroke
				(width 0.0254)
				(type default)
			)
			(layer "B.Fab")
		)
		(fp_line
			(start 0.254 -0.508)
			(end -0.254 -0.508)
			(stroke
				(width 0.0254)
				(type default)
			)
			(layer "B.Fab")
		)
		(fp_line
			(start 0.254 0.508)
			(end 0.254 -0.508)
			(stroke
				(width 0.0254)
				(type default)
			)
			(layer "B.Fab")
		)
		(pad "1" smd rect
			(at 0 -0.4191 180)
			(size 0.508 0.5334)
			(layers "B.Cu" "B.Mask" "B.Paste")
			(net "NFP_CORE_VID1")
		)
		(pad "2" smd rect
			(at 0 0.4191 180)
			(size 0.508 0.5334)
			(layers "B.Cu" "B.Mask" "B.Paste")
			(net "_NFP_CORE_VID1")
		)
		(zone
			(layer "B.Cu")
			(hatch none 0.5)
			(connect_pads
				(clearance 0)
			)
			(min_thickness 0.25)
			(keepout
				(tracks not_allowed)
				(vias allowed)
				(pads allowed)
				(copperpour not_allowed)
				(footprints allowed)
			)
			(placement
				(enabled no)
				(sheetname "")
			)
			(fill
				(thermal_gap 0.5)
				(thermal_bridge_width 0.5)
				(island_removal_mode 0)
			)
			(polygon
				(pts
					(xy 28.2956 32.6136) (xy 28.2956 32.6644) (xy 28.3464 32.6644) (xy 28.3464 32.6136)
				)
			)
		)
	)
	(footprint ""
		(layer "B.Cu")
		(at 42.237025 7.542022 180)
		(property "Reference" "C270"
			(at -0.408305 2.843022 270)
			(unlocked yes)
			(layer "B.SilkS")
			(effects
				(font
					(size 0.7874 0.5842)
					(thickness 0.127)
				)
				(justify mirror)
			)
		)
		(property "Value" ""
			(at 0 0 0)
			(layer "B.Fab")
			(effects
				(font
					(size 1.27 1.27)
				)
				(justify mirror)
			)
		)
		(duplicate_pad_numbers_are_jumpers no)
		(fp_circle
			(center 0 0)
			(end -0.104648 0)
			(stroke
				(width 0.1016)
				(type default)
			)
			(fill no)
			(layer "B.SilkS")
		)
		(fp_poly
			(pts
				(xy 0.381 -0.889) (xy 0.381 0.889) (xy -0.381 0.889) (xy -0.381 -0.889)
			)
			(stroke
				(width 0)
				(type default)
			)
			(fill no)
			(layer "B.CrtYd")
		)
		(fp_line
			(start 0.508 1.016)
			(end 0.508 -1.016)
			(stroke
				(width 0.0254)
				(type default)
			)
			(layer "B.Fab")
		)
		(fp_line
			(start 0.508 -1.016)
			(end 0.254 -1.016)
			(stroke
				(width 0.0254)
				(type default)
			)
			(layer "B.Fab")
		)
		(fp_line
			(start 0.254 -1.016)
			(end -0.508 -1.016)
			(stroke
				(width 0.0254)
				(type default)
			)
			(layer "B.Fab")
		)
		(fp_line
			(start -0.508 1.016)
			(end 0.508 1.016)
			(stroke
				(width 0.0254)
				(type default)
			)
			(layer "B.Fab")
		)
		(fp_line
			(start -0.508 -1.016)
			(end -0.508 1.016)
			(stroke
				(width 0.0254)
				(type default)
			)
			(layer "B.Fab")
		)
		(pad "1" smd custom
			(at 0 -0.500126)
			(size 0.127 0.127)
			(layers "B.Cu" "B.Mask" "B.Paste")
			(net "VDD_1.2V")
			(options
				(clearance outline)
				(anchor circle)
			)
			(primitives
				(gr_poly
					(pts
						(xy -0.1778 0.254) (xy 0.1778 0.254) (xy 0.254 0.1778) (xy 0.254 -0.1778) (xy 0.1778 -0.254) (xy -0.1778 -0.254)
						(xy -0.254 -0.1778) (xy -0.254 0.1778)
					)
					(width 0)
					(fill yes)
				)
			)
		)
		(pad "2" smd custom
			(at 0 0.500126)
			(size 0.127 0.127)
			(layers "B.Cu" "B.Mask" "B.Paste")
			(net "GND")
			(options
				(clearance outline)
				(anchor circle)
			)
			(primitives
				(gr_poly
					(pts
						(xy -0.1778 0.254) (xy 0.1778 0.254) (xy 0.254 0.1778) (xy 0.254 -0.1778) (xy 0.1778 -0.254) (xy -0.1778 -0.254)
						(xy -0.254 -0.1778) (xy -0.254 0.1778)
					)
					(width 0)
					(fill yes)
				)
			)
		)
	)
	(footprint ""
		(layer "B.Cu")
		(at 37.973 18.415 -90)
		(property "Reference" "R201"
			(at 0 0 90)
			(layer "B.SilkS")
			(hide yes)
			(effects
				(font
					(size 1.27 1.27)
				)
				(justify mirror)
			)
		)
		(property "Value" "39.0"
			(at 0.148158 1.3462 180)
			(unlocked yes)
			(layer "B.Fab")
			(hide yes)
			(effects
				(font
					(size 1.27 0.9652)
					(thickness 0.000001)
				)
				(justify left mirror)
			)
		)
		(property "Device Type" "REST0108"
			(at 0.148158 1.3462 180)
			(unlocked yes)
			(layer "B.Fab")
			(hide yes)
			(effects
				(font
					(size 1.27 0.9652)
					(thickness 0.000001)
				)
				(justify left mirror)
			)
		)
		(duplicate_pad_numbers_are_jumpers no)
		(fp_poly
			(pts
				(xy -0.635 1.0668) (xy -0.635 -1.0668) (xy 0.635 -1.0668) (xy 0.635 1.0668)
			)
			(stroke
				(width 0)
				(type default)
			)
			(fill no)
			(layer "B.CrtYd")
		)
		(fp_line
			(start -0.254 0.508)
			(end 0.254 0.508)
			(stroke
				(width 0.0254)
				(type default)
			)
			(layer "B.Fab")
		)
		(fp_line
			(start 0.254 0.508)
			(end 0.254 -0.508)
			(stroke
				(width 0.0254)
				(type default)
			)
			(layer "B.Fab")
		)
		(fp_line
			(start -0.254 -0.508)
			(end -0.254 0.508)
			(stroke
				(width 0.0254)
				(type default)
			)
			(layer "B.Fab")
		)
		(fp_line
			(start 0.254 -0.508)
			(end -0.254 -0.508)
			(stroke
				(width 0.0254)
				(type default)
			)
			(layer "B.Fab")
		)
		(pad "1" smd rect
			(at 0 -0.4191 90)
			(size 0.508 0.5334)
			(layers "B.Cu" "B.Mask" "B.Paste")
			(net "_NFP_ARM_SPI_FLASH_MOSI")
		)
		(pad "2" smd rect
			(at 0 0.4191 90)
			(size 0.508 0.5334)
			(layers "B.Cu" "B.Mask" "B.Paste")
			(net "NFP_ARM_SPI_FLASH_MOSI")
		)
		(zone
			(layer "B.Cu")
			(hatch none 0.5)
			(connect_pads
				(clearance 0)
			)
			(min_thickness 0.25)
			(keepout
				(tracks not_allowed)
				(vias allowed)
				(pads allowed)
				(copperpour not_allowed)
				(footprints allowed)
			)
			(placement
				(enabled no)
				(sheetname "")
			)
			(fill
				(thermal_gap 0.5)
				(thermal_bridge_width 0.5)
				(island_removal_mode 0)
			)
			(polygon
				(pts
					(xy 37.9984 18.3896) (xy 37.9476 18.3896) (xy 37.9476 18.4404) (xy 37.9984 18.4404)
				)
			)
		)
	)
	(footprint ""
		(layer "B.Cu")
		(at 44.237021 9.542018 180)
		(property "Reference" "C277"
			(at 0 0 0)
			(layer "B.SilkS")
			(hide yes)
			(effects
				(font
					(size 1.27 1.27)
				)
				(justify mirror)
			)
		)
		(property "Value" ""
			(at 0 0 0)
			(layer "B.Fab")
			(effects
				(font
					(size 1.27 1.27)
				)
				(justify mirror)
			)
		)
		(duplicate_pad_numbers_are_jumpers no)
		(fp_circle
			(center 0 0)
			(end -0.104648 0)
			(stroke
				(width 0.1016)
				(type default)
			)
			(fill no)
			(layer "B.SilkS")
		)
		(fp_poly
			(pts
				(xy 0.381 -0.889) (xy 0.381 0.889) (xy -0.381 0.889) (xy -0.381 -0.889)
			)
			(stroke
				(width 0)
				(type default)
			)
			(fill no)
			(layer "B.CrtYd")
		)
		(fp_line
			(start 0.508 1.016)
			(end 0.508 -1.016)
			(stroke
				(width 0.0254)
				(type default)
			)
			(layer "B.Fab")
		)
		(fp_line
			(start 0.508 -1.016)
			(end 0.254 -1.016)
			(stroke
				(width 0.0254)
				(type default)
			)
			(layer "B.Fab")
		)
		(fp_line
			(start 0.254 -1.016)
			(end -0.508 -1.016)
			(stroke
				(width 0.0254)
				(type default)
			)
			(layer "B.Fab")
		)
		(fp_line
			(start -0.508 1.016)
			(end 0.508 1.016)
			(stroke
				(width 0.0254)
				(type default)
			)
			(layer "B.Fab")
		)
		(fp_line
			(start -0.508 -1.016)
			(end -0.508 1.016)
			(stroke
				(width 0.0254)
				(type default)
			)
			(layer "B.Fab")
		)
		(pad "1" smd custom
			(at 0 -0.500126)
			(size 0.127 0.127)
			(layers "B.Cu" "B.Mask" "B.Paste")
			(net "VDD_3.3V")
			(options
				(clearance outline)
				(anchor circle)
			)
			(primitives
				(gr_poly
					(pts
						(xy -0.1778 0.254) (xy 0.1778 0.254) (xy 0.254 0.1778) (xy 0.254 -0.1778) (xy 0.1778 -0.254) (xy -0.1778 -0.254)
						(xy -0.254 -0.1778) (xy -0.254 0.1778)
					)
					(width 0)
					(fill yes)
				)
			)
		)
		(pad "2" smd custom
			(at 0 0.500126)
			(size 0.127 0.127)
			(layers "B.Cu" "B.Mask" "B.Paste")
			(net "GND")
			(options
				(clearance outline)
				(anchor circle)
			)
			(primitives
				(gr_poly
					(pts
						(xy -0.1778 0.254) (xy 0.1778 0.254) (xy 0.254 0.1778) (xy 0.254 -0.1778) (xy 0.1778 -0.254) (xy -0.1778 -0.254)
						(xy -0.254 -0.1778) (xy -0.254 0.1778)
					)
					(width 0)
					(fill yes)
				)
			)
		)
	)
	(footprint ""
		(layer "B.Cu")
		(at 24.638 32.639 180)
		(property "Reference" "C123"
			(at -0.22733 -4.953 270)
			(unlocked yes)
			(layer "B.SilkS")
			(effects
				(font
					(size 0.7874 0.5842)
					(thickness 0.127)
				)
				(justify left mirror)
			)
		)
		(property "Value" "0.1UF"
			(at 0.091846 0.2921 90)
			(unlocked yes)
			(layer "B.Fab")
			(hide yes)
			(effects
				(font
					(size 0.7874 0.5842)
					(thickness 0.2032)
				)
				(justify left mirror)
			)
		)
		(property "Device Type" "CAPC0073"
			(at 0.091846 0.2921 90)
			(unlocked yes)
			(layer "B.Fab")
			(hide yes)
			(effects
				(font
					(size 0.7874 0.5842)
					(thickness 0.2032)
				)
				(justify left mirror)
			)
		)
		(duplicate_pad_numbers_are_jumpers no)
		(fp_poly
			(pts
				(xy -0.635 1.0668) (xy -0.635 -1.0668) (xy 0.635 -1.0668) (xy 0.635 1.0668)
			)
			(stroke
				(width 0)
				(type default)
			)
			(fill no)
			(layer "B.CrtYd")
		)
		(fp_line
			(start 0.254 0.508)
			(end 0.254 -0.508)
			(stroke
				(width 0.0254)
				(type default)
			)
			(layer "B.Fab")
		)
		(fp_line
			(start 0.254 -0.508)
			(end -0.254 -0.508)
			(stroke
				(width 0.0254)
				(type default)
			)
			(layer "B.Fab")
		)
		(fp_line
			(start -0.254 0.508)
			(end 0.254 0.508)
			(stroke
				(width 0.0254)
				(type default)
			)
			(layer "B.Fab")
		)
		(fp_line
			(start -0.254 -0.508)
			(end -0.254 0.508)
			(stroke
				(width 0.0254)
				(type default)
			)
			(layer "B.Fab")
		)
		(pad "1" smd rect
			(at 0 -0.4191)
			(size 0.508 0.5334)
			(layers "B.Cu" "B.Mask" "B.Paste")
			(net "EXT_3.3V")
		)
		(pad "2" smd rect
			(at 0 0.4191)
			(size 0.508 0.5334)
			(layers "B.Cu" "B.Mask" "B.Paste")
			(net "GND")
		)
		(zone
			(layer "B.Cu")
			(hatch none 0.5)
			(connect_pads
				(clearance 0)
			)
			(min_thickness 0.25)
			(keepout
				(tracks not_allowed)
				(vias allowed)
				(pads allowed)
				(copperpour not_allowed)
				(footprints allowed)
			)
			(placement
				(enabled no)
				(sheetname "")
			)
			(fill
				(thermal_gap 0.5)
				(thermal_bridge_width 0.5)
				(island_removal_mode 0)
			)
			(polygon
				(pts
					(xy 24.6634 32.6644) (xy 24.6634 32.6136) (xy 24.6126 32.6136) (xy 24.6126 32.6644)
				)
			)
		)
	)
	(footprint ""
		(layer "B.Cu")
		(at 81.850992 13.456006)
		(property "Reference" "V2_A-A03"
			(at 0 0 0)
			(layer "B.SilkS")
			(hide yes)
			(effects
				(font
					(size 1.27 1.27)
				)
				(justify mirror)
			)
		)
		(property "Value" ""
			(at 0 0 0)
			(layer "B.Fab")
			(effects
				(font
					(size 1.27 1.27)
				)
				(justify mirror)
			)
		)
		(duplicate_pad_numbers_are_jumpers no)
		(pad "1" thru_hole circle
			(at 0 0 180)
			(size 0.4572 0.4572)
			(drill 0.20574)
			(layers "*.Cu" "*.Mask")
			(remove_unused_layers no)
			(net "DDR0_32A_A3")
			(clearance 0.1143)
			(thermal_gap 0.1143)
		)
	)
	(footprint ""
		(layer "B.Cu")
		(at 76.251003 25.013006)
		(property "Reference" "V_A-CB6"
			(at 0 0 0)
			(layer "B.SilkS")
			(hide yes)
			(effects
				(font
					(size 1.27 1.27)
				)
				(justify mirror)
			)
		)
		(property "Value" ""
			(at 0 0 0)
			(layer "B.Fab")
			(effects
				(font
					(size 1.27 1.27)
				)
				(justify mirror)
			)
		)
		(duplicate_pad_numbers_are_jumpers no)
		(pad "1" thru_hole circle
			(at 0 0 180)
			(size 0.4572 0.4572)
			(drill 0.20574)
			(layers "*.Cu" "*.Mask")
			(remove_unused_layers no)
			(net "DDR0_32A_CB6")
			(clearance 0.1143)
			(thermal_gap 0.1143)
		)
	)
	(footprint ""
		(layer "B.Cu")
		(at 35.179 48.641 90)
		(property "Reference" "TP57"
			(at 0 0 90)
			(layer "B.SilkS")
			(hide yes)
			(effects
				(font
					(size 1.27 1.27)
				)
				(justify mirror)
			)
		)
		(property "Value" "*"
			(at 0.4826 -0.14732 90)
			(unlocked yes)
			(layer "B.Fab")
			(hide yes)
			(effects
				(font
					(size 1.27 0.9652)
					(thickness 0.000001)
				)
				(justify left mirror)
			)
		)
		(property "Device Type" "TP_SMALL"
			(at 0.4826 -0.14732 90)
			(unlocked yes)
			(layer "B.Fab")
			(hide yes)
			(effects
				(font
					(size 1.27 0.9652)
					(thickness 0.000001)
				)
				(justify left mirror)
			)
		)
		(duplicate_pad_numbers_are_jumpers no)
		(fp_line
			(start 0.8636 -0.8636)
			(end 0.8636 0.8636)
			(stroke
				(width 0.1524)
				(type default)
			)
			(layer "B.SilkS")
		)
		(fp_line
			(start -0.8636 -0.8636)
			(end 0.8636 -0.8636)
			(stroke
				(width 0.1524)
				(type default)
			)
			(layer "B.SilkS")
		)
		(fp_line
			(start 0.8636 0.8636)
			(end -0.8636 0.8636)
			(stroke
				(width 0.1524)
				(type default)
			)
			(layer "B.SilkS")
		)
		(fp_line
			(start -0.8636 0.8636)
			(end -0.8636 -0.8636)
			(stroke
				(width 0.1524)
				(type default)
			)
			(layer "B.SilkS")
		)
		(fp_poly
			(pts
				(xy 0.635 -0.635) (xy 0.635 0.635) (xy -0.635 0.635) (xy -0.635 -0.635)
			)
			(stroke
				(width 0)
				(type default)
			)
			(fill no)
			(layer "B.CrtYd")
		)
		(pad "1" smd rect
			(at 0 0 270)
			(size 1.27 1.27)
			(layers "B.Cu" "B.Mask" "B.Paste")
			(net "CNTRL_SPI_SCK")
		)
	)
	(footprint ""
		(layer "B.Cu")
		(at 56.736996 8.042021 90)
		(property "Reference" "C91"
			(at 0 0 90)
			(layer "B.SilkS")
			(hide yes)
			(effects
				(font
					(size 1.27 1.27)
				)
				(justify mirror)
			)
		)
		(property "Value" ""
			(at 0 0 90)
			(layer "B.Fab")
			(effects
				(font
					(size 1.27 1.27)
				)
				(justify mirror)
			)
		)
		(duplicate_pad_numbers_are_jumpers no)
		(fp_circle
			(center 0 0)
			(end 0 0.104648)
			(stroke
				(width 0.1016)
				(type default)
			)
			(fill no)
			(layer "B.SilkS")
		)
		(fp_poly
			(pts
				(xy 0.381 -0.889) (xy 0.381 0.889) (xy -0.381 0.889) (xy -0.381 -0.889)
			)
			(stroke
				(width 0)
				(type default)
			)
			(fill no)
			(layer "B.CrtYd")
		)
		(fp_line
			(start 0.508 -1.016)
			(end 0.254 -1.016)
			(stroke
				(width 0.0254)
				(type default)
			)
			(layer "B.Fab")
		)
		(fp_line
			(start 0.254 -1.016)
			(end -0.508 -1.016)
			(stroke
				(width 0.0254)
				(type default)
			)
			(layer "B.Fab")
		)
		(fp_line
			(start -0.508 -1.016)
			(end -0.508 1.016)
			(stroke
				(width 0.0254)
				(type default)
			)
			(layer "B.Fab")
		)
		(fp_line
			(start 0.508 1.016)
			(end 0.508 -1.016)
			(stroke
				(width 0.0254)
				(type default)
			)
			(layer "B.Fab")
		)
		(fp_line
			(start -0.508 1.016)
			(end 0.508 1.016)
			(stroke
				(width 0.0254)
				(type default)
			)
			(layer "B.Fab")
		)
		(pad "1" smd custom
			(at 0 -0.500126 270)
			(size 0.127 0.127)
			(layers "B.Cu" "B.Mask" "B.Paste")
			(net "VDDAH_PCIE0")
			(options
				(clearance outline)
				(anchor circle)
			)
			(primitives
				(gr_poly
					(pts
						(xy -0.1778 0.254) (xy 0.1778 0.254) (xy 0.254 0.1778) (xy 0.254 -0.1778) (xy 0.1778 -0.254) (xy -0.1778 -0.254)
						(xy -0.254 -0.1778) (xy -0.254 0.1778)
					)
					(width 0)
					(fill yes)
				)
			)
		)
		(pad "2" smd custom
			(at 0 0.500126 270)
			(size 0.127 0.127)
			(layers "B.Cu" "B.Mask" "B.Paste")
			(net "GND")
			(options
				(clearance outline)
				(anchor circle)
			)
			(primitives
				(gr_poly
					(pts
						(xy -0.1778 0.254) (xy 0.1778 0.254) (xy 0.254 0.1778) (xy 0.254 -0.1778) (xy 0.1778 -0.254) (xy -0.1778 -0.254)
						(xy -0.254 -0.1778) (xy -0.254 0.1778)
					)
					(width 0)
					(fill yes)
				)
			)
		)
	)
	(footprint ""
		(layer "B.Cu")
		(at 42.237025 25.541986)
		(property "Reference" "R199"
			(at 0 0 0)
			(layer "B.SilkS")
			(hide yes)
			(effects
				(font
					(size 1.27 1.27)
				)
				(justify mirror)
			)
		)
		(property "Value" ""
			(at 0 0 0)
			(layer "B.Fab")
			(effects
				(font
					(size 1.27 1.27)
				)
				(justify mirror)
			)
		)
		(duplicate_pad_numbers_are_jumpers no)
		(fp_circle
			(center 0 0)
			(end 0.104648 0)
			(stroke
				(width 0.1016)
				(type default)
			)
			(fill no)
			(layer "B.SilkS")
		)
		(fp_poly
			(pts
				(xy 0.381 -0.889) (xy 0.381 0.889) (xy -0.381 0.889) (xy -0.381 -0.889)
			)
			(stroke
				(width 0)
				(type default)
			)
			(fill no)
			(layer "B.CrtYd")
		)
		(fp_line
			(start -0.508 -1.016)
			(end -0.508 1.016)
			(stroke
				(width 0.0254)
				(type default)
			)
			(layer "B.Fab")
		)
		(fp_line
			(start -0.508 1.016)
			(end 0.508 1.016)
			(stroke
				(width 0.0254)
				(type default)
			)
			(layer "B.Fab")
		)
		(fp_line
			(start 0.254 -1.016)
			(end -0.508 -1.016)
			(stroke
				(width 0.0254)
				(type default)
			)
			(layer "B.Fab")
		)
		(fp_line
			(start 0.508 -1.016)
			(end 0.254 -1.016)
			(stroke
				(width 0.0254)
				(type default)
			)
			(layer "B.Fab")
		)
		(fp_line
			(start 0.508 1.016)
			(end 0.508 -1.016)
			(stroke
				(width 0.0254)
				(type default)
			)
			(layer "B.Fab")
		)
		(pad "1" smd custom
			(at 0 -0.500126 180)
			(size 0.127 0.127)
			(layers "B.Cu" "B.Mask" "B.Paste")
			(net "_NFP_SPI2_SCK")
			(options
				(clearance outline)
				(anchor circle)
			)
			(primitives
				(gr_poly
					(pts
						(xy -0.1778 0.254) (xy 0.1778 0.254) (xy 0.254 0.1778) (xy 0.254 -0.1778) (xy 0.1778 -0.254) (xy -0.1778 -0.254)
						(xy -0.254 -0.1778) (xy -0.254 0.1778)
					)
					(width 0)
					(fill yes)
				)
			)
		)
		(pad "2" smd custom
			(at 0 0.500126 180)
			(size 0.127 0.127)
			(layers "B.Cu" "B.Mask" "B.Paste")
			(net "NFP_SPI2_SCK")
			(options
				(clearance outline)
				(anchor circle)
			)
			(primitives
				(gr_poly
					(pts
						(xy -0.1778 0.254) (xy 0.1778 0.254) (xy 0.254 0.1778) (xy 0.254 -0.1778) (xy 0.1778 -0.254) (xy -0.1778 -0.254)
						(xy -0.254 -0.1778) (xy -0.254 0.1778)
					)
					(width 0)
					(fill yes)
				)
			)
		)
	)
)
